(kicad_pcb
	(version 20260206)
	(generator "pcbnew")
	(generator_version "10.0")
	(general
		(thickness 1.6)
		(legacy_teardrops no)
	)
	(paper "A4")
	(title_block
		(title "03242023_DA0F0TMBIJ0_F0T_Motherboard_J_brd_V01_OCP.brd")
		(comment 1 "Grand Teton / footprints 1707-1711 of 6105")
	)
	(layers
		(0 "F.Cu" signal "TOP")
		(4 "In1.Cu" signal "GND")
		(6 "In2.Cu" signal "IN1")
		(8 "In3.Cu" signal "GND1")
		(10 "In4.Cu" signal "IN2")
		(12 "In5.Cu" signal "GND2")
		(14 "In6.Cu" signal "IN3")
		(16 "In7.Cu" signal "GND3")
		(18 "In8.Cu" signal "VCC")
		(20 "In9.Cu" signal "VCC1")
		(22 "In10.Cu" signal "GND4")
		(24 "In11.Cu" signal "IN4")
		(26 "In12.Cu" signal "GND5")
		(28 "In13.Cu" signal "IN5")
		(30 "In14.Cu" signal "GND6")
		(32 "In15.Cu" signal "IN6")
		(34 "In16.Cu" signal "GND7")
		(2 "B.Cu" signal "BOTTOM")
		(9 "F.Adhes" user "F.Adhesive")
		(11 "B.Adhes" user "B.Adhesive")
		(13 "F.Paste" user "Package Geometry/Pastemask Top")
		(15 "B.Paste" user "Package Geometry/Pastemask Bottom")
		(5 "F.SilkS" user "Ref Des/Silkscreen Top")
		(7 "B.SilkS" user "Ref Des/Silkscreen Bottom")
		(1 "F.Mask" user "Board Geometry/Soldermask Top")
		(3 "B.Mask" user "Board Geometry/Soldermask Bottom")
		(17 "Dwgs.User" user "User.Drawings")
		(19 "Cmts.User" user "User.Comments")
		(21 "Eco1.User" user "User.Eco1")
		(23 "Eco2.User" user "User.Eco2")
		(25 "Edge.Cuts" user "Board Geometry/Outline")
		(27 "Margin" user)
		(31 "F.CrtYd" user "Package Geometry/Place Bound Top")
		(29 "B.CrtYd" user "Package Geometry/Place Bound Bottom")
		(35 "F.Fab" user "Ref Des/Assembly Top")
		(33 "B.Fab" user "Ref Des/Assembly Bottom")
	)
	(footprint ""
		(layer "F.Cu")
		(at 366.3696 -407.0604)
		(property "Reference" "R4740"
			(at 0 0 0)
			(layer "F.SilkS")
			(hide yes)
			(effects
				(font
					(size 1.27 1.27)
				)
			)
		)
		(property "Value" ""
			(at 0 0 0)
			(layer "F.Fab")
			(effects
				(font
					(size 1.27 1.27)
				)
			)
		)
		(duplicate_pad_numbers_are_jumpers no)
		(fp_line
			(start -0.7874 -0.4064)
			(end 0.7874 -0.4064)
			(stroke
				(width 0.1524)
				(type default)
			)
			(layer "F.SilkS")
		)
		(fp_line
			(start -0.7874 0.4064)
			(end -0.7874 -0.4064)
			(stroke
				(width 0.1524)
				(type default)
			)
			(layer "F.SilkS")
		)
		(fp_line
			(start 0.7874 -0.4064)
			(end 0.7874 0.4064)
			(stroke
				(width 0.1524)
				(type default)
			)
			(layer "F.SilkS")
		)
		(fp_line
			(start 0.7874 0.4064)
			(end -0.7874 0.4064)
			(stroke
				(width 0.1524)
				(type default)
			)
			(layer "F.SilkS")
		)
		(fp_line
			(start -0.67945 -0.305054)
			(end -0.12065 -0.305054)
			(stroke
				(width 0.1)
				(type default)
			)
			(layer "F.Fab")
		)
		(fp_line
			(start -0.67945 0.3048)
			(end -0.67945 -0.305054)
			(stroke
				(width 0.1)
				(type default)
			)
			(layer "F.Fab")
		)
		(fp_line
			(start -0.12065 -0.305054)
			(end -0.12065 -0.2794)
			(stroke
				(width 0.1)
				(type default)
			)
			(layer "F.Fab")
		)
		(fp_line
			(start -0.12065 -0.2794)
			(end 0.12065 -0.2794)
			(stroke
				(width 0.1)
				(type default)
			)
			(layer "F.Fab")
		)
		(fp_line
			(start -0.12065 0.2794)
			(end -0.12065 0.3048)
			(stroke
				(width 0.1)
				(type default)
			)
			(layer "F.Fab")
		)
		(fp_line
			(start -0.12065 0.3048)
			(end -0.67945 0.3048)
			(stroke
				(width 0.1)
				(type default)
			)
			(layer "F.Fab")
		)
		(fp_line
			(start 0.120396 0.2794)
			(end -0.12065 0.2794)
			(stroke
				(width 0.1)
				(type default)
			)
			(layer "F.Fab")
		)
		(fp_line
			(start 0.120396 0.3048)
			(end 0.120396 0.2794)
			(stroke
				(width 0.1)
				(type default)
			)
			(layer "F.Fab")
		)
		(fp_line
			(start 0.12065 -0.3048)
			(end 0.67945 -0.3048)
			(stroke
				(width 0.1)
				(type default)
			)
			(layer "F.Fab")
		)
		(fp_line
			(start 0.12065 -0.2794)
			(end 0.12065 -0.3048)
			(stroke
				(width 0.1)
				(type default)
			)
			(layer "F.Fab")
		)
		(fp_line
			(start 0.67945 -0.3048)
			(end 0.67945 0.3048)
			(stroke
				(width 0.1)
				(type default)
			)
			(layer "F.Fab")
		)
		(fp_line
			(start 0.67945 0.3048)
			(end 0.120396 0.3048)
			(stroke
				(width 0.1)
				(type default)
			)
			(layer "F.Fab")
		)
		(pad "1" smd circle
			(at -0.40005 0)
			(size 0 0)
			(layers "F.Cu" "F.Mask" "F.Paste")
			(net "P3V3_AUX")
		)
		(pad "2" smd circle
			(at 0.40005 0)
			(size 0 0)
			(layers "F.Cu" "F.Mask" "F.Paste")
			(net "PRSNT_CABLE_SWB_B1_ISO_N")
		)
	)
	(footprint ""
		(layer "F.Cu")
		(at 378.099574 5.463794 180)
		(property "Reference" "J66"
			(at -4.451096 -1.394206 90)
			(unlocked yes)
			(layer "F.SilkS")
			(effects
				(font
					(size 0.7874 0.5842)
					(thickness 0.1524)
				)
				(justify left)
			)
		)
		(property "Value" ""
			(at 0 0 180)
			(layer "F.Fab")
			(effects
				(font
					(size 1.27 1.27)
				)
			)
		)
		(duplicate_pad_numbers_are_jumpers no)
		(fp_line
			(start 1.2192 2.1082)
			(end -1.2192 2.1082)
			(stroke
				(width 0.1524)
				(type default)
			)
			(layer "F.SilkS")
		)
		(fp_line
			(start 1.2192 -2.1082)
			(end 1.2192 2.1082)
			(stroke
				(width 0.1524)
				(type default)
			)
			(layer "F.SilkS")
		)
		(fp_line
			(start -1.2192 2.1082)
			(end -1.2192 -2.1082)
			(stroke
				(width 0.1524)
				(type default)
			)
			(layer "F.SilkS")
		)
		(fp_line
			(start -1.2192 -2.1082)
			(end 1.2192 -2.1082)
			(stroke
				(width 0.1524)
				(type default)
			)
			(layer "F.SilkS")
		)
		(pad "" np_thru_hole circle
			(at -2.8829 -1.27 90)
			(size 1.0414 1.0414)
			(drill 1.0414)
			(layers "*.Cu" "*.Mask")
			(clearance 0.381)
			(thermal_gap 0.381)
		)
		(pad "" np_thru_hole circle
			(at -2.8829 1.27 90)
			(size 1.0414 1.0414)
			(drill 1.0414)
			(layers "*.Cu" "*.Mask")
			(clearance 0.381)
			(thermal_gap 0.381)
		)
		(pad "" np_thru_hole circle
			(at 3.4671 -1.27 90)
			(size 1.0414 1.0414)
			(drill 1.0414)
			(layers "*.Cu" "*.Mask")
			(clearance 0.381)
			(thermal_gap 0.381)
		)
		(pad "" np_thru_hole circle
			(at 3.4671 1.27 90)
			(size 1.0414 1.0414)
			(drill 1.0414)
			(layers "*.Cu" "*.Mask")
			(clearance 0.381)
			(thermal_gap 0.381)
		)
		(pad "1" smd rect
			(at 0.8255 -0.249936 90)
			(size 0.3048 0.508)
			(layers "F.Cu" "F.Mask" "F.Paste")
			(net "DELTA_L_85_5INCH_IN2_DP")
		)
		(pad "2" smd rect
			(at 0.8255 0.249936 90)
			(size 0.3048 0.508)
			(layers "F.Cu" "F.Mask" "F.Paste")
			(net "DELTA_L_85_5INCH_IN2_DN")
		)
		(pad "3" smd circle
			(at 0 0 180)
			(size 0 0)
			(layers "F.Cu" "F.Mask" "F.Paste")
			(net "DELTA_L_GND_1")
		)
		(zone
			(layer "F.Cu")
			(hatch none 0.5)
			(connect_pads
				(clearance 0)
			)
			(min_thickness 0.25)
			(keepout
				(tracks not_allowed)
				(vias allowed)
				(pads allowed)
				(copperpour not_allowed)
				(footprints allowed)
			)
			(placement
				(enabled no)
				(sheetname "")
			)
			(fill
				(thermal_gap 0.5)
				(thermal_bridge_width 0.5)
				(island_removal_mode 0)
			)
			(polygon
				(pts
					(xy 376.981974 6.012434) (xy 376.981974 5.91693) (xy 377.578874 5.91693) (xy 377.578874 5.51053)
					(xy 376.981974 5.51053) (xy 376.981974 5.417058) (xy 377.578874 5.417058) (xy 377.578874 5.010658)
					(xy 376.981974 5.010658) (xy 376.981974 4.915154) (xy 377.680474 4.915154) (xy 377.680474 6.012434)
				)
			)
		)
		(zone
			(layers "F.Cu" "B.Cu" "In1.Cu" "In2.Cu" "In3.Cu" "In4.Cu" "In5.Cu" "In6.Cu"
				"In7.Cu" "In8.Cu" "In9.Cu" "In10.Cu" "In11.Cu" "In12.Cu" "In13.Cu" "In14.Cu"
				"In15.Cu" "In16.Cu"
			)
			(hatch none 0.5)
			(connect_pads
				(clearance 0)
			)
			(min_thickness 0.25)
			(keepout
				(tracks not_allowed)
				(vias allowed)
				(pads allowed)
				(copperpour not_allowed)
				(footprints allowed)
			)
			(placement
				(enabled no)
				(sheetname "")
			)
			(fill
				(thermal_gap 0.5)
				(thermal_bridge_width 0.5)
				(island_removal_mode 0)
			)
			(polygon
				(pts
					(arc
						(start 375.559574 4.193794)
						(mid 373.705374 4.193794)
						(end 375.559574 4.193794)
					)
				)
			)
		)
		(zone
			(layers "F.Cu" "B.Cu" "In1.Cu" "In2.Cu" "In3.Cu" "In4.Cu" "In5.Cu" "In6.Cu"
				"In7.Cu" "In8.Cu" "In9.Cu" "In10.Cu" "In11.Cu" "In12.Cu" "In13.Cu" "In14.Cu"
				"In15.Cu" "In16.Cu"
			)
			(hatch none 0.5)
			(connect_pads
				(clearance 0)
			)
			(min_thickness 0.25)
			(keepout
				(tracks not_allowed)
				(vias allowed)
				(pads allowed)
				(copperpour not_allowed)
				(footprints allowed)
			)
			(placement
				(enabled no)
				(sheetname "")
			)
			(fill
				(thermal_gap 0.5)
				(thermal_bridge_width 0.5)
				(island_removal_mode 0)
			)
			(polygon
				(pts
					(arc
						(start 375.559574 6.733794)
						(mid 373.705374 6.733794)
						(end 375.559574 6.733794)
					)
				)
			)
		)
		(zone
			(layers "F.Cu" "B.Cu" "In1.Cu" "In2.Cu" "In3.Cu" "In4.Cu" "In5.Cu" "In6.Cu"
				"In7.Cu" "In8.Cu" "In9.Cu" "In10.Cu" "In11.Cu" "In12.Cu" "In13.Cu" "In14.Cu"
				"In15.Cu" "In16.Cu"
			)
			(hatch none 0.5)
			(connect_pads
				(clearance 0)
			)
			(min_thickness 0.25)
			(keepout
				(tracks not_allowed)
				(vias allowed)
				(pads allowed)
				(copperpour not_allowed)
				(footprints allowed)
			)
			(placement
				(enabled no)
				(sheetname "")
			)
			(fill
				(thermal_gap 0.5)
				(thermal_bridge_width 0.5)
				(island_removal_mode 0)
			)
			(polygon
				(pts
					(arc
						(start 381.909574 4.193794)
						(mid 380.055374 4.193794)
						(end 381.909574 4.193794)
					)
				)
			)
		)
		(zone
			(layers "F.Cu" "B.Cu" "In1.Cu" "In2.Cu" "In3.Cu" "In4.Cu" "In5.Cu" "In6.Cu"
				"In7.Cu" "In8.Cu" "In9.Cu" "In10.Cu" "In11.Cu" "In12.Cu" "In13.Cu" "In14.Cu"
				"In15.Cu" "In16.Cu"
			)
			(hatch none 0.5)
			(connect_pads
				(clearance 0)
			)
			(min_thickness 0.25)
			(keepout
				(tracks not_allowed)
				(vias allowed)
				(pads allowed)
				(copperpour not_allowed)
				(footprints allowed)
			)
			(placement
				(enabled no)
				(sheetname "")
			)
			(fill
				(thermal_gap 0.5)
				(thermal_bridge_width 0.5)
				(island_removal_mode 0)
			)
			(polygon
				(pts
					(arc
						(start 381.909574 6.733794)
						(mid 380.055374 6.733794)
						(end 381.909574 6.733794)
					)
				)
			)
		)
	)
	(footprint ""
		(layer "F.Cu")
		(at 411.201108 -363.193584)
		(property "Reference" "PR444"
			(at 0 0 0)
			(layer "F.SilkS")
			(hide yes)
			(effects
				(font
					(size 1.27 1.27)
				)
			)
		)
		(property "Value" ""
			(at 0 0 0)
			(layer "F.Fab")
			(effects
				(font
					(size 1.27 1.27)
				)
			)
		)
		(duplicate_pad_numbers_are_jumpers no)
		(fp_line
			(start -0.7874 -0.4064)
			(end 0.7874 -0.4064)
			(stroke
				(width 0.1524)
				(type default)
			)
			(layer "F.SilkS")
		)
		(fp_line
			(start -0.7874 0.4064)
			(end -0.7874 -0.4064)
			(stroke
				(width 0.1524)
				(type default)
			)
			(layer "F.SilkS")
		)
		(fp_line
			(start 0.7874 -0.4064)
			(end 0.7874 0.4064)
			(stroke
				(width 0.1524)
				(type default)
			)
			(layer "F.SilkS")
		)
		(fp_line
			(start 0.7874 0.4064)
			(end -0.7874 0.4064)
			(stroke
				(width 0.1524)
				(type default)
			)
			(layer "F.SilkS")
		)
		(fp_line
			(start -0.67945 -0.305054)
			(end -0.12065 -0.305054)
			(stroke
				(width 0.1)
				(type default)
			)
			(layer "F.Fab")
		)
		(fp_line
			(start -0.67945 0.3048)
			(end -0.67945 -0.305054)
			(stroke
				(width 0.1)
				(type default)
			)
			(layer "F.Fab")
		)
		(fp_line
			(start -0.12065 -0.305054)
			(end -0.12065 -0.2794)
			(stroke
				(width 0.1)
				(type default)
			)
			(layer "F.Fab")
		)
		(fp_line
			(start -0.12065 -0.2794)
			(end 0.12065 -0.2794)
			(stroke
				(width 0.1)
				(type default)
			)
			(layer "F.Fab")
		)
		(fp_line
			(start -0.12065 0.2794)
			(end -0.12065 0.3048)
			(stroke
				(width 0.1)
				(type default)
			)
			(layer "F.Fab")
		)
		(fp_line
			(start -0.12065 0.3048)
			(end -0.67945 0.3048)
			(stroke
				(width 0.1)
				(type default)
			)
			(layer "F.Fab")
		)
		(fp_line
			(start 0.120396 0.2794)
			(end -0.12065 0.2794)
			(stroke
				(width 0.1)
				(type default)
			)
			(layer "F.Fab")
		)
		(fp_line
			(start 0.120396 0.3048)
			(end 0.120396 0.2794)
			(stroke
				(width 0.1)
				(type default)
			)
			(layer "F.Fab")
		)
		(fp_line
			(start 0.12065 -0.3048)
			(end 0.67945 -0.3048)
			(stroke
				(width 0.1)
				(type default)
			)
			(layer "F.Fab")
		)
		(fp_line
			(start 0.12065 -0.2794)
			(end 0.12065 -0.3048)
			(stroke
				(width 0.1)
				(type default)
			)
			(layer "F.Fab")
		)
		(fp_line
			(start 0.67945 -0.3048)
			(end 0.67945 0.3048)
			(stroke
				(width 0.1)
				(type default)
			)
			(layer "F.Fab")
		)
		(fp_line
			(start 0.67945 0.3048)
			(end 0.120396 0.3048)
			(stroke
				(width 0.1)
				(type default)
			)
			(layer "F.Fab")
		)
		(pad "1" smd circle
			(at -0.40005 0)
			(size 0 0)
			(layers "F.Cu" "F.Mask" "F.Paste")
			(net "P5V")
		)
		(pad "2" smd circle
			(at 0.40005 0)
			(size 0 0)
			(layers "F.Cu" "F.Mask" "F.Paste")
			(net "PVCCFA_EHV_FIVRA_CPU0_PVCC1")
		)
	)
	(footprint ""
		(layer "F.Cu")
		(at 218.08948 -128.819148 180)
		(property "Reference" "R1691"
			(at 0 0 180)
			(layer "F.SilkS")
			(hide yes)
			(effects
				(font
					(size 1.27 1.27)
				)
			)
		)
		(property "Value" ""
			(at 0 0 180)
			(layer "F.Fab")
			(effects
				(font
					(size 1.27 1.27)
				)
			)
		)
		(duplicate_pad_numbers_are_jumpers no)
		(fp_line
			(start 0.7874 0.4064)
			(end -0.7874 0.4064)
			(stroke
				(width 0.1524)
				(type default)
			)
			(layer "F.SilkS")
		)
		(fp_line
			(start 0.7874 -0.4064)
			(end 0.7874 0.4064)
			(stroke
				(width 0.1524)
				(type default)
			)
			(layer "F.SilkS")
		)
		(fp_line
			(start -0.7874 0.4064)
			(end -0.7874 -0.4064)
			(stroke
				(width 0.1524)
				(type default)
			)
			(layer "F.SilkS")
		)
		(fp_line
			(start -0.7874 -0.4064)
			(end 0.7874 -0.4064)
			(stroke
				(width 0.1524)
				(type default)
			)
			(layer "F.SilkS")
		)
		(fp_line
			(start 0.67945 0.3048)
			(end 0.120396 0.3048)
			(stroke
				(width 0.1)
				(type default)
			)
			(layer "F.Fab")
		)
		(fp_line
			(start 0.67945 -0.3048)
			(end 0.67945 0.3048)
			(stroke
				(width 0.1)
				(type default)
			)
			(layer "F.Fab")
		)
		(fp_line
			(start 0.12065 -0.2794)
			(end 0.12065 -0.3048)
			(stroke
				(width 0.1)
				(type default)
			)
			(layer "F.Fab")
		)
		(fp_line
			(start 0.12065 -0.3048)
			(end 0.67945 -0.3048)
			(stroke
				(width 0.1)
				(type default)
			)
			(layer "F.Fab")
		)
		(fp_line
			(start 0.120396 0.3048)
			(end 0.120396 0.2794)
			(stroke
				(width 0.1)
				(type default)
			)
			(layer "F.Fab")
		)
		(fp_line
			(start 0.120396 0.2794)
			(end -0.12065 0.2794)
			(stroke
				(width 0.1)
				(type default)
			)
			(layer "F.Fab")
		)
		(fp_line
			(start -0.12065 0.3048)
			(end -0.67945 0.3048)
			(stroke
				(width 0.1)
				(type default)
			)
			(layer "F.Fab")
		)
		(fp_line
			(start -0.12065 0.2794)
			(end -0.12065 0.3048)
			(stroke
				(width 0.1)
				(type default)
			)
			(layer "F.Fab")
		)
		(fp_line
			(start -0.12065 -0.2794)
			(end 0.12065 -0.2794)
			(stroke
				(width 0.1)
				(type default)
			)
			(layer "F.Fab")
		)
		(fp_line
			(start -0.12065 -0.305054)
			(end -0.12065 -0.2794)
			(stroke
				(width 0.1)
				(type default)
			)
			(layer "F.Fab")
		)
		(fp_line
			(start -0.67945 0.3048)
			(end -0.67945 -0.305054)
			(stroke
				(width 0.1)
				(type default)
			)
			(layer "F.Fab")
		)
		(fp_line
			(start -0.67945 -0.305054)
			(end -0.12065 -0.305054)
			(stroke
				(width 0.1)
				(type default)
			)
			(layer "F.Fab")
		)
		(pad "1" smd circle
			(at -0.40005 0 180)
			(size 0 0)
			(layers "F.Cu" "F.Mask" "F.Paste")
			(net "P3V3_AUX")
		)
		(pad "2" smd circle
			(at 0.40005 0 180)
			(size 0 0)
			(layers "F.Cu" "F.Mask" "F.Paste")
			(net "PWRGD_DSW_PWROK_R1")
		)
	)
	(footprint ""
		(layer "F.Cu")
		(at 329.948794 -21.625052 180)
		(property "Reference" "R1269"
			(at 0 0 180)
			(layer "F.SilkS")
			(hide yes)
			(effects
				(font
					(size 1.27 1.27)
				)
			)
		)
		(property "Value" ""
			(at 0 0 180)
			(layer "F.Fab")
			(effects
				(font
					(size 1.27 1.27)
				)
			)
		)
		(duplicate_pad_numbers_are_jumpers no)
		(fp_line
			(start 0.7874 0.4064)
			(end -0.7874 0.4064)
			(stroke
				(width 0.1524)
				(type default)
			)
			(layer "F.SilkS")
		)
		(fp_line
			(start 0.7874 -0.4064)
			(end 0.7874 0.4064)
			(stroke
				(width 0.1524)
				(type default)
			)
			(layer "F.SilkS")
		)
		(fp_line
			(start -0.7874 0.4064)
			(end -0.7874 -0.4064)
			(stroke
				(width 0.1524)
				(type default)
			)
			(layer "F.SilkS")
		)
		(fp_line
			(start -0.7874 -0.4064)
			(end 0.7874 -0.4064)
			(stroke
				(width 0.1524)
				(type default)
			)
			(layer "F.SilkS")
		)
		(fp_line
			(start 0.67945 0.3048)
			(end 0.120396 0.3048)
			(stroke
				(width 0.1)
				(type default)
			)
			(layer "F.Fab")
		)
		(fp_line
			(start 0.67945 -0.3048)
			(end 0.67945 0.3048)
			(stroke
				(width 0.1)
				(type default)
			)
			(layer "F.Fab")
		)
		(fp_line
			(start 0.12065 -0.2794)
			(end 0.12065 -0.3048)
			(stroke
				(width 0.1)
				(type default)
			)
			(layer "F.Fab")
		)
		(fp_line
			(start 0.12065 -0.3048)
			(end 0.67945 -0.3048)
			(stroke
				(width 0.1)
				(type default)
			)
			(layer "F.Fab")
		)
		(fp_line
			(start 0.120396 0.3048)
			(end 0.120396 0.2794)
			(stroke
				(width 0.1)
				(type default)
			)
			(layer "F.Fab")
		)
		(fp_line
			(start 0.120396 0.2794)
			(end -0.12065 0.2794)
			(stroke
				(width 0.1)
				(type default)
			)
			(layer "F.Fab")
		)
		(fp_line
			(start -0.12065 0.3048)
			(end -0.67945 0.3048)
			(stroke
				(width 0.1)
				(type default)
			)
			(layer "F.Fab")
		)
		(fp_line
			(start -0.12065 0.2794)
			(end -0.12065 0.3048)
			(stroke
				(width 0.1)
				(type default)
			)
			(layer "F.Fab")
		)
		(fp_line
			(start -0.12065 -0.2794)
			(end 0.12065 -0.2794)
			(stroke
				(width 0.1)
				(type default)
			)
			(layer "F.Fab")
		)
		(fp_line
			(start -0.12065 -0.305054)
			(end -0.12065 -0.2794)
			(stroke
				(width 0.1)
				(type default)
			)
			(layer "F.Fab")
		)
		(fp_line
			(start -0.67945 0.3048)
			(end -0.67945 -0.305054)
			(stroke
				(width 0.1)
				(type default)
			)
			(layer "F.Fab")
		)
		(fp_line
			(start -0.67945 -0.305054)
			(end -0.12065 -0.305054)
			(stroke
				(width 0.1)
				(type default)
			)
			(layer "F.Fab")
		)
		(pad "1" smd circle
			(at -0.40005 0 180)
			(size 0 0)
			(layers "F.Cu" "F.Mask" "F.Paste")
			(net "IRQ_BMC_PCH_NMI")
		)
		(pad "2" smd circle
			(at 0.40005 0 180)
			(size 0 0)
			(layers "F.Cu" "F.Mask" "F.Paste")
			(net "GND")
		)
	)
)
